# T6G (Grand Teton) — schematic netlist excerpt (pin names and nets, part order shuffled) for the footprints in the layout excerpt that follows; sources: Cadence DE-HDL packaged netlist, KiCad conversion of 04192023_DAF0TMB3IC0_F0TG_MB_C_brd_V02_OCP.brd

C1925  Q_CAP  0.1UF 25V 10% X7R  pkg 0402  page 144 : A = P3V3_M2_0 ; B = GND
R142  Q_RES  0 5% EMPTY  pkg 0402LF  page 161 : A = SMB_CPU0_CPU1_APML_MUX1_SCL ; B = SMB_APML_CPU0_R_SCL

(kicad_pcb
	(version 20260206)
	(generator "pcbnew")
	(generator_version "10.0")
	(general
		(thickness 1.6)
		(legacy_teardrops no)
	)
	(paper "A4")
	(title_block
		(title "04192023_DAF0TMB3IC0_F0TG_MB_C_brd_V02_OCP.brd")
		(comment 1 "Grand Teton / footprints 7693-7694 of 8354")
	)
	(layers
		(0 "F.Cu" signal "TOP")
		(4 "In1.Cu" signal "GND")
		(6 "In2.Cu" signal "IN1")
		(8 "In3.Cu" signal "GND1")
		(10 "In4.Cu" signal "IN2")
		(12 "In5.Cu" signal "GND2")
		(14 "In6.Cu" signal "IN3")
		(16 "In7.Cu" signal "GND3")
		(18 "In8.Cu" signal "VCC")
		(20 "In9.Cu" signal "VCC1")
		(22 "In10.Cu" signal "GND4")
		(24 "In11.Cu" signal "IN4")
		(26 "In12.Cu" signal "GND5")
		(28 "In13.Cu" signal "IN5")
		(30 "In14.Cu" signal "GND6")
		(32 "In15.Cu" signal "IN6")
		(34 "In16.Cu" signal "GND7")
		(2 "B.Cu" signal "BOTTOM")
		(9 "F.Adhes" user "F.Adhesive")
		(11 "B.Adhes" user "B.Adhesive")
		(13 "F.Paste" user "Package Geometry/Pastemask Top")
		(15 "B.Paste" user "Package Geometry/Pastemask Bottom")
		(5 "F.SilkS" user "Ref Des/Silkscreen Top")
		(7 "B.SilkS" user "Ref Des/Silkscreen Bottom")
		(1 "F.Mask" user "Board Geometry/Soldermask Top")
		(3 "B.Mask" user "Board Geometry/Soldermask Bottom")
		(17 "Dwgs.User" user "User.Drawings")
		(19 "Cmts.User" user "User.Comments")
		(21 "Eco1.User" user "User.Eco1")
		(23 "Eco2.User" user "User.Eco2")
		(25 "Edge.Cuts" user "Board Geometry/Outline")
		(27 "Margin" user)
		(31 "F.CrtYd" user "Package Geometry/Place Bound Top")
		(29 "B.CrtYd" user "Package Geometry/Place Bound Bottom")
		(35 "F.Fab" user "Ref Des/Assembly Top")
		(33 "B.Fab" user "Ref Des/Assembly Bottom")
	)
	(footprint ""
		(layer "B.Cu")
		(at 232.156 -240.03 180)
		(property "Reference" "R142"
			(at 0 0 0)
			(layer "B.SilkS")
			(hide yes)
			(effects
				(font
					(size 1.27 1.27)
				)
				(justify mirror)
			)
		)
		(property "Value" ""
			(at 0 0 0)
			(layer "B.Fab")
			(effects
				(font
					(size 1.27 1.27)
				)
				(justify mirror)
			)
		)
		(duplicate_pad_numbers_are_jumpers no)
		(fp_line
			(start 0.7874 0.4064)
			(end 0.7874 -0.4064)
			(stroke
				(width 0.1524)
				(type default)
			)
			(layer "B.SilkS")
		)
		(fp_line
			(start 0.7874 -0.4064)
			(end -0.7874 -0.4064)
			(stroke
				(width 0.1524)
				(type default)
			)
			(layer "B.SilkS")
		)
		(fp_line
			(start -0.7874 0.4064)
			(end 0.7874 0.4064)
			(stroke
				(width 0.1524)
				(type default)
			)
			(layer "B.SilkS")
		)
		(fp_line
			(start -0.7874 -0.4064)
			(end -0.7874 0.4064)
			(stroke
				(width 0.1524)
				(type default)
			)
			(layer "B.SilkS")
		)
		(fp_line
			(start 0.67945 0.3048)
			(end 0.67945 -0.305054)
			(stroke
				(width 0.1)
				(type default)
			)
			(layer "B.Fab")
		)
		(fp_line
			(start 0.67945 -0.305054)
			(end 0.12065 -0.305054)
			(stroke
				(width 0.1)
				(type default)
			)
			(layer "B.Fab")
		)
		(fp_line
			(start 0.12065 0.3048)
			(end 0.67945 0.3048)
			(stroke
				(width 0.1)
				(type default)
			)
			(layer "B.Fab")
		)
		(fp_line
			(start 0.12065 0.2794)
			(end 0.12065 0.3048)
			(stroke
				(width 0.1)
				(type default)
			)
			(layer "B.Fab")
		)
		(fp_line
			(start 0.12065 -0.2794)
			(end -0.12065 -0.2794)
			(stroke
				(width 0.1)
				(type default)
			)
			(layer "B.Fab")
		)
		(fp_line
			(start 0.12065 -0.305054)
			(end 0.12065 -0.2794)
			(stroke
				(width 0.1)
				(type default)
			)
			(layer "B.Fab")
		)
		(fp_line
			(start -0.120396 0.3048)
			(end -0.120396 0.2794)
			(stroke
				(width 0.1)
				(type default)
			)
			(layer "B.Fab")
		)
		(fp_line
			(start -0.120396 0.2794)
			(end 0.12065 0.2794)
			(stroke
				(width 0.1)
				(type default)
			)
			(layer "B.Fab")
		)
		(fp_line
			(start -0.12065 -0.2794)
			(end -0.12065 -0.3048)
			(stroke
				(width 0.1)
				(type default)
			)
			(layer "B.Fab")
		)
		(fp_line
			(start -0.12065 -0.3048)
			(end -0.67945 -0.3048)
			(stroke
				(width 0.1)
				(type default)
			)
			(layer "B.Fab")
		)
		(fp_line
			(start -0.67945 0.3048)
			(end -0.120396 0.3048)
			(stroke
				(width 0.1)
				(type default)
			)
			(layer "B.Fab")
		)
		(fp_line
			(start -0.67945 -0.3048)
			(end -0.67945 0.3048)
			(stroke
				(width 0.1)
				(type default)
			)
			(layer "B.Fab")
		)
		(pad "1" smd circle
			(at 0.40005 0)
			(size 0 0)
			(layers "B.Cu" "B.Mask" "B.Paste")
			(net "SMB_CPU0_CPU1_APML_MUX1_SCL")
		)
		(pad "2" smd circle
			(at -0.40005 0)
			(size 0 0)
			(layers "B.Cu" "B.Mask" "B.Paste")
			(net "SMB_APML_CPU0_R_SCL")
		)
	)
	(footprint ""
		(layer "B.Cu")
		(at 169.66692 -51.399948 180)
		(property "Reference" "C1925"
			(at 0 0 0)
			(layer "B.SilkS")
			(hide yes)
			(effects
				(font
					(size 1.27 1.27)
				)
				(justify mirror)
			)
		)
		(property "Value" ""
			(at 0 0 0)
			(layer "B.Fab")
			(effects
				(font
					(size 1.27 1.27)
				)
				(justify mirror)
			)
		)
		(duplicate_pad_numbers_are_jumpers no)
		(fp_line
			(start 0.7874 0.4064)
			(end 0.7874 -0.4064)
			(stroke
				(width 0.1524)
				(type default)
			)
			(layer "B.SilkS")
		)
		(fp_line
			(start 0.7874 -0.4064)
			(end -0.7874 -0.4064)
			(stroke
				(width 0.1524)
				(type default)
			)
			(layer "B.SilkS")
		)
		(fp_line
			(start -0.7874 0.4064)
			(end 0.7874 0.4064)
			(stroke
				(width 0.1524)
				(type default)
			)
			(layer "B.SilkS")
		)
		(fp_line
			(start -0.7874 -0.4064)
			(end -0.7874 0.4064)
			(stroke
				(width 0.1524)
				(type default)
			)
			(layer "B.SilkS")
		)
		(fp_line
			(start 0.67945 0.3048)
			(end 0.67945 -0.305054)
			(stroke
				(width 0.1)
				(type default)
			)
			(layer "B.Fab")
		)
		(fp_line
			(start 0.67945 -0.305054)
			(end 0.12065 -0.305054)
			(stroke
				(width 0.1)
				(type default)
			)
			(layer "B.Fab")
		)
		(fp_line
			(start 0.12065 0.3048)
			(end 0.67945 0.3048)
			(stroke
				(width 0.1)
				(type default)
			)
			(layer "B.Fab")
		)
		(fp_line
			(start 0.12065 0.2794)
			(end 0.12065 0.3048)
			(stroke
				(width 0.1)
				(type default)
			)
			(layer "B.Fab")
		)
		(fp_line
			(start 0.12065 -0.2794)
			(end -0.12065 -0.2794)
			(stroke
				(width 0.1)
				(type default)
			)
			(layer "B.Fab")
		)
		(fp_line
			(start 0.12065 -0.305054)
			(end 0.12065 -0.2794)
			(stroke
				(width 0.1)
				(type default)
			)
			(layer "B.Fab")
		)
		(fp_line
			(start -0.120396 0.3048)
			(end -0.120396 0.2794)
			(stroke
				(width 0.1)
				(type default)
			)
			(layer "B.Fab")
		)
		(fp_line
			(start -0.120396 0.2794)
			(end 0.12065 0.2794)
			(stroke
				(width 0.1)
				(type default)
			)
			(layer "B.Fab")
		)
		(fp_line
			(start -0.12065 -0.2794)
			(end -0.12065 -0.3048)
			(stroke
				(width 0.1)
				(type default)
			)
			(layer "B.Fab")
		)
		(fp_line
			(start -0.12065 -0.3048)
			(end -0.67945 -0.3048)
			(stroke
				(width 0.1)
				(type default)
			)
			(layer "B.Fab")
		)
		(fp_line
			(start -0.67945 0.3048)
			(end -0.120396 0.3048)
			(stroke
				(width 0.1)
				(type default)
			)
			(layer "B.Fab")
		)
		(fp_line
			(start -0.67945 -0.3048)
			(end -0.67945 0.3048)
			(stroke
				(width 0.1)
				(type default)
			)
			(layer "B.Fab")
		)
		(pad "1" smd circle
			(at 0.40005 0)
			(size 0 0)
			(layers "B.Cu" "B.Mask" "B.Paste")
			(net "P3V3_M2_0")
		)
		(pad "2" smd circle
			(at -0.40005 0)
			(size 0 0)
			(layers "B.Cu" "B.Mask" "B.Paste")
			(net "GND")
		)
	)
)
